# BASEBOARD_FAB2 (Tioga Pass) — schematic netlist excerpt (pin names and nets, part order shuffled) for the footprints in the layout excerpt that follows; sources: Cadence DE-HDL packaged netlist, KiCad conversion of Wiwynn_Tioga_Pass_MB.brd

C2L37  CAP_A  0.01UF 25V 10% X7R  pkg 0402V  page 173 : A = SATA6G_P4_TX_C_DN ; B = SATA6G_PCH_PCIE_UP_SATA_TXN<4>
R2T66  RES  0.0 5% CHIP  pkg 0402  page 93 : A = FM_CPU_ERR1_LVT3_R_N ; B = FM_CPU_ERR1_LVT3_K_N
C5P25  CAP  47UF 4V 20% X6S  pkg 0805  page 42 : A = PVCCIN_CPU0 ; B = GND

(kicad_pcb
	(version 20260206)
	(generator "pcbnew")
	(generator_version "10.0")
	(general
		(thickness 1.6)
		(legacy_teardrops no)
	)
	(paper "A4")
	(title_block
		(title "Wiwynn_Tioga_Pass_MB.brd")
		(comment 1 "Tioga Pass / footprints 4243-4245 of 4770")
	)
	(layers
		(0 "F.Cu" signal "TOP")
		(4 "In1.Cu" signal "L2GND")
		(6 "In2.Cu" signal "L3")
		(8 "In3.Cu" signal "L4GND")
		(10 "In4.Cu" signal "L5")
		(12 "In5.Cu" signal "L6GND")
		(14 "In6.Cu" signal "L7VCC")
		(16 "In7.Cu" signal "L8VCC")
		(18 "In8.Cu" signal "L9GND")
		(20 "In9.Cu" signal "L10")
		(22 "In10.Cu" signal "L11GND")
		(24 "In11.Cu" signal "L12")
		(26 "In12.Cu" signal "L13GND")
		(2 "B.Cu" signal "BOTTOM")
		(9 "F.Adhes" user "F.Adhesive")
		(11 "B.Adhes" user "B.Adhesive")
		(13 "F.Paste" user "Package Geometry/Pastemask Top")
		(15 "B.Paste" user "Package Geometry/Pastemask Bottom")
		(5 "F.SilkS" user "Ref Des/Silkscreen Top")
		(7 "B.SilkS" user "Ref Des/Silkscreen Bottom")
		(1 "F.Mask" user "Board Geometry/Soldermask Top")
		(3 "B.Mask" user "Board Geometry/Soldermask Bottom")
		(17 "Dwgs.User" user "User.Drawings")
		(19 "Cmts.User" user "User.Comments")
		(21 "Eco1.User" user "User.Eco1")
		(23 "Eco2.User" user "User.Eco2")
		(25 "Edge.Cuts" user "Board Geometry/Outline")
		(27 "Margin" user)
		(31 "F.CrtYd" user "Package Geometry/Place Bound Top")
		(29 "B.CrtYd" user "Package Geometry/Place Bound Bottom")
		(35 "F.Fab" user "Ref Des/Assembly Top")
		(33 "B.Fab" user "Ref Des/Assembly Bottom")
	)
	(footprint ""
		(layer "B.Cu")
		(at 414.5534 -142.0368 -90)
		(property "Reference" "C2L37"
			(at 0 0 90)
			(layer "B.SilkS")
			(hide yes)
			(effects
				(font
					(size 1.27 1.27)
				)
				(justify mirror)
			)
		)
		(property "Value" ""
			(at 0 0 90)
			(layer "B.Fab")
			(effects
				(font
					(size 1.27 1.27)
				)
				(justify mirror)
			)
		)
		(duplicate_pad_numbers_are_jumpers no)
		(fp_poly
			(pts
				(xy -0.3048 -0.1016) (xy -0.3048 0.9906) (xy 0.3048 0.9906) (xy 0.3048 -0.1016)
			)
			(stroke
				(width 0)
				(type default)
			)
			(fill no)
			(layer "B.CrtYd")
		)
		(fp_line
			(start -0.3048 0.9906)
			(end -0.3048 -0.1016)
			(stroke
				(width 0.1)
				(type default)
			)
			(layer "B.Fab")
		)
		(fp_line
			(start 0.3048 0.9906)
			(end -0.3048 0.9906)
			(stroke
				(width 0.1)
				(type default)
			)
			(layer "B.Fab")
		)
		(fp_line
			(start -0.3048 -0.1016)
			(end 0.3048 -0.1016)
			(stroke
				(width 0.1)
				(type default)
			)
			(layer "B.Fab")
		)
		(fp_line
			(start 0.3048 -0.1016)
			(end 0.3048 0.9906)
			(stroke
				(width 0.1)
				(type default)
			)
			(layer "B.Fab")
		)
		(pad "1" smd rect
			(at 0 0 90)
			(size 0.508 0.508)
			(layers "B.Cu" "B.Mask" "B.Paste")
			(net "SATA6G_P4_TX_C_DN")
		)
		(pad "2" smd rect
			(at 0 0.889 90)
			(size 0.508 0.508)
			(layers "B.Cu" "B.Mask" "B.Paste")
			(net "SATA6G_PCH_PCIE_UP_SATA_TXN<4>")
		)
		(zone
			(layer "B.Cu")
			(hatch none 0.5)
			(connect_pads
				(clearance 0)
			)
			(min_thickness 0.25)
			(keepout
				(tracks not_allowed)
				(vias allowed)
				(pads allowed)
				(copperpour not_allowed)
				(footprints allowed)
			)
			(placement
				(enabled no)
				(sheetname "")
			)
			(fill
				(thermal_gap 0.5)
				(thermal_bridge_width 0.5)
				(island_removal_mode 0)
			)
			(polygon
				(pts
					(xy 413.9184 -141.7828) (xy 413.9184 -142.2908) (xy 414.2994 -142.2908) (xy 414.2994 -141.7828)
				)
			)
		)
		(zone
			(layer "B.Cu")
			(hatch none 0.5)
			(connect_pads
				(clearance 0)
			)
			(min_thickness 0.25)
			(keepout
				(tracks allowed)
				(vias not_allowed)
				(pads allowed)
				(copperpour not_allowed)
				(footprints allowed)
			)
			(placement
				(enabled no)
				(sheetname "")
			)
			(fill
				(thermal_gap 0.5)
				(thermal_bridge_width 0.5)
				(island_removal_mode 0)
			)
			(polygon
				(pts
					(xy 414.2994 -141.7828) (xy 414.2994 -142.2908) (xy 413.9184 -142.2908) (xy 413.9184 -141.7828)
				)
			)
		)
	)
	(footprint ""
		(layer "B.Cu")
		(at 362.270294 -44.020486)
		(property "Reference" "R2T66"
			(at 0 0 0)
			(layer "B.SilkS")
			(hide yes)
			(effects
				(font
					(size 1.27 1.27)
				)
				(justify mirror)
			)
		)
		(property "Value" ""
			(at 0 0 0)
			(layer "B.Fab")
			(effects
				(font
					(size 1.27 1.27)
				)
				(justify mirror)
			)
		)
		(duplicate_pad_numbers_are_jumpers no)
		(fp_poly
			(pts
				(xy 0.2794 -0.1016) (xy -0.2794 -0.1016) (xy -0.2794 0.9906) (xy 0.2794 0.9906)
			)
			(stroke
				(width 0)
				(type default)
			)
			(fill no)
			(layer "B.CrtYd")
		)
		(fp_line
			(start -0.2794 -0.1016)
			(end 0.2794 -0.1016)
			(stroke
				(width 0.1)
				(type default)
			)
			(layer "B.Fab")
		)
		(fp_line
			(start -0.2794 0.9906)
			(end -0.2794 -0.1016)
			(stroke
				(width 0.1)
				(type default)
			)
			(layer "B.Fab")
		)
		(fp_line
			(start 0.2794 -0.1016)
			(end 0.2794 0.9906)
			(stroke
				(width 0.1)
				(type default)
			)
			(layer "B.Fab")
		)
		(fp_line
			(start 0.2794 0.9906)
			(end -0.2794 0.9906)
			(stroke
				(width 0.1)
				(type default)
			)
			(layer "B.Fab")
		)
		(pad "1" smd rect
			(at 0 0 180)
			(size 0.508 0.508)
			(layers "B.Cu" "B.Mask" "B.Paste")
			(net "FM_CPU_ERR1_LVT3_R_N")
		)
		(pad "2" smd rect
			(at 0 0.889 180)
			(size 0.508 0.508)
			(layers "B.Cu" "B.Mask" "B.Paste")
			(net "FM_CPU_ERR1_LVT3_K_N")
		)
		(zone
			(layer "B.Cu")
			(hatch none 0.5)
			(connect_pads
				(clearance 0)
			)
			(min_thickness 0.25)
			(keepout
				(tracks allowed)
				(vias not_allowed)
				(pads allowed)
				(copperpour not_allowed)
				(footprints allowed)
			)
			(placement
				(enabled no)
				(sheetname "")
			)
			(fill
				(thermal_gap 0.5)
				(thermal_bridge_width 0.5)
				(island_removal_mode 0)
			)
			(polygon
				(pts
					(xy 362.524294 -43.766486) (xy 362.016294 -43.766486) (xy 362.016294 -43.385486) (xy 362.524294 -43.385486)
				)
			)
		)
		(zone
			(layer "B.Cu")
			(hatch none 0.5)
			(connect_pads
				(clearance 0)
			)
			(min_thickness 0.25)
			(keepout
				(tracks not_allowed)
				(vias allowed)
				(pads allowed)
				(copperpour not_allowed)
				(footprints allowed)
			)
			(placement
				(enabled no)
				(sheetname "")
			)
			(fill
				(thermal_gap 0.5)
				(thermal_bridge_width 0.5)
				(island_removal_mode 0)
			)
			(polygon
				(pts
					(xy 362.524294 -43.385486) (xy 362.016294 -43.385486) (xy 362.016294 -43.766486) (xy 362.524294 -43.766486)
				)
			)
		)
	)
	(footprint ""
		(layer "B.Cu")
		(at 262.206486 -77.82814)
		(property "Reference" "C5P25"
			(at 0 0 0)
			(layer "B.SilkS")
			(hide yes)
			(effects
				(font
					(size 1.27 1.27)
				)
				(justify mirror)
			)
		)
		(property "Value" ""
			(at 0 0 0)
			(layer "B.Fab")
			(effects
				(font
					(size 1.27 1.27)
				)
				(justify mirror)
			)
		)
		(duplicate_pad_numbers_are_jumpers no)
		(fp_poly
			(pts
				(xy 0.7239 -0.2159) (xy -0.7239 -0.2159) (xy -0.7239 1.9939) (xy 0.7239 1.9939)
			)
			(stroke
				(width 0)
				(type default)
			)
			(fill no)
			(layer "B.CrtYd")
		)
		(fp_line
			(start -0.7239 -0.2159)
			(end 0.7239 -0.2159)
			(stroke
				(width 0.1)
				(type default)
			)
			(layer "B.Fab")
		)
		(fp_line
			(start -0.7239 1.9939)
			(end -0.7239 -0.2159)
			(stroke
				(width 0.1)
				(type default)
			)
			(layer "B.Fab")
		)
		(fp_line
			(start 0.7239 -0.2159)
			(end 0.7239 1.9939)
			(stroke
				(width 0.1)
				(type default)
			)
			(layer "B.Fab")
		)
		(fp_line
			(start 0.7239 1.9939)
			(end -0.7239 1.9939)
			(stroke
				(width 0.1)
				(type default)
			)
			(layer "B.Fab")
		)
		(pad "1" smd rect
			(at 0 0 180)
			(size 1.27 1.016)
			(layers "B.Cu" "B.Mask" "B.Paste")
			(net "PVCCIN_CPU0")
		)
		(pad "2" smd rect
			(at 0 1.778 180)
			(size 1.27 1.016)
			(layers "B.Cu" "B.Mask" "B.Paste")
			(net "GND")
		)
		(zone
			(layer "B.Cu")
			(hatch none 0.5)
			(connect_pads
				(clearance 0)
			)
			(min_thickness 0.25)
			(keepout
				(tracks not_allowed)
				(vias allowed)
				(pads allowed)
				(copperpour not_allowed)
				(footprints allowed)
			)
			(placement
				(enabled no)
				(sheetname "")
			)
			(fill
				(thermal_gap 0.5)
				(thermal_bridge_width 0.5)
				(island_removal_mode 0)
			)
			(polygon
				(pts
					(xy 262.841486 -77.32014) (xy 261.571486 -77.32014) (xy 261.571486 -76.55814) (xy 262.841486 -76.55814)
				)
			)
		)
	)
)
